(kicad_pcb
	(version 20260206)
	(generator "pcbnew")
	(generator_version "10.0")
	(general
		(thickness 1.6)
		(legacy_teardrops no)
	)
	(paper "A4")
	(title_block
		(title "04192023_DAF0TMB3IC0_F0TG_MB_C_brd_V02_OCP.brd")
		(comment 1 "Grand Teton / footprint 3955 of 8354 (U25), pads 1-109 of 6102")
	)
	(layers
		(0 "F.Cu" signal "TOP")
		(4 "In1.Cu" signal "GND")
		(6 "In2.Cu" signal "IN1")
		(8 "In3.Cu" signal "GND1")
		(10 "In4.Cu" signal "IN2")
		(12 "In5.Cu" signal "GND2")
		(14 "In6.Cu" signal "IN3")
		(16 "In7.Cu" signal "GND3")
		(18 "In8.Cu" signal "VCC")
		(20 "In9.Cu" signal "VCC1")
		(22 "In10.Cu" signal "GND4")
		(24 "In11.Cu" signal "IN4")
		(26 "In12.Cu" signal "GND5")
		(28 "In13.Cu" signal "IN5")
		(30 "In14.Cu" signal "GND6")
		(32 "In15.Cu" signal "IN6")
		(34 "In16.Cu" signal "GND7")
		(2 "B.Cu" signal "BOTTOM")
		(9 "F.Adhes" user "F.Adhesive")
		(11 "B.Adhes" user "B.Adhesive")
		(13 "F.Paste" user "Package Geometry/Pastemask Top")
		(15 "B.Paste" user "Package Geometry/Pastemask Bottom")
		(5 "F.SilkS" user "Ref Des/Silkscreen Top")
		(7 "B.SilkS" user "Ref Des/Silkscreen Bottom")
		(1 "F.Mask" user "Board Geometry/Soldermask Top")
		(3 "B.Mask" user "Board Geometry/Soldermask Bottom")
		(17 "Dwgs.User" user "User.Drawings")
		(19 "Cmts.User" user "User.Comments")
		(21 "Eco1.User" user "User.Eco1")
		(23 "Eco2.User" user "User.Eco2")
		(25 "Edge.Cuts" user "Board Geometry/Outline")
		(27 "Margin" user)
		(31 "F.CrtYd" user "Package Geometry/Place Bound Top")
		(29 "B.CrtYd" user "Package Geometry/Place Bound Bottom")
		(35 "F.Fab" user "Ref Des/Assembly Top")
		(33 "B.Fab" user "Ref Des/Assembly Bottom")
	)
	(footprint ""
		(layer "F.Cu")
		(at 359.867962 -258.880102 180)
		(property "Reference" "U25"
			(at -45.78477 -62.086744 0)
			(unlocked yes)
			(layer "F.SilkS")
			(effects
				(font
					(size 0.7874 0.5842)
					(thickness 0.1524)
				)
			)
		)
		(property "Value" ""
			(at 0 0 180)
			(layer "F.Fab")
			(effects
				(font
					(size 1.27 1.27)
				)
			)
		)
		(duplicate_pad_numbers_are_jumpers no)
		(pad "" np_thru_hole circle
			(at -42.099992 0 180)
			(size 4.0132 4.0132)
			(drill 4.0132)
			(layers "*.Cu" "*.Mask")
			(clearance 0.381)
			(thermal_gap 0.381)
		)
		(pad "" np_thru_hole circle
			(at -30.599888 -45.900086 180)
			(size 4.0132 4.0132)
			(drill 4.0132)
			(layers "*.Cu" "*.Mask")
			(clearance 0.381)
			(thermal_gap 0.381)
		)
		(pad "" np_thru_hole circle
			(at -30.599888 45.900086 180)
			(size 4.0132 4.0132)
			(drill 4.0132)
			(layers "*.Cu" "*.Mask")
			(clearance 0.381)
			(thermal_gap 0.381)
		)
		(pad "" np_thru_hole circle
			(at 30.599888 -45.900086 180)
			(size 4.0132 4.0132)
			(drill 4.0132)
			(layers "*.Cu" "*.Mask")
			(clearance 0.381)
			(thermal_gap 0.381)
		)
		(pad "" np_thru_hole circle
			(at 30.599888 45.900086 180)
			(size 4.0132 4.0132)
			(drill 4.0132)
			(layers "*.Cu" "*.Mask")
			(clearance 0.381)
			(thermal_gap 0.381)
		)
		(pad "" np_thru_hole circle
			(at 42.099992 0 180)
			(size 4.0132 4.0132)
			(drill 4.0132)
			(layers "*.Cu" "*.Mask")
			(clearance 0.381)
			(thermal_gap 0.381)
		)
		(pad "A3" smd circle
			(at -32.280098 -36.809934 180)
			(size 0.450088 0.450088)
			(layers "F.Cu" "F.Mask" "F.Paste")
			(net "GND")
		)
		(pad "A4" smd circle
			(at -31.340044 -36.809934 180)
			(size 0.450088 0.450088)
			(layers "F.Cu" "F.Mask" "F.Paste")
			(net "SMB_CPU0_3_R_SCL")
		)
		(pad "A5" smd circle
			(at -30.39999 -36.809934 180)
			(size 0.450088 0.450088)
			(layers "F.Cu" "F.Mask" "F.Paste")
			(net "I3C_1_SPD_DDRGL_CPU0_R_SDA")
		)
		(pad "A7" smd circle
			(at -28.519882 -36.809934 180)
			(size 0.450088 0.450088)
			(layers "F.Cu" "F.Mask" "F.Paste")
			(net "CLK_100M_CPU0_CLK01_R_DN")
		)
		(pad "A8" smd circle
			(at -27.580082 -36.809934 180)
			(size 0.450088 0.450088)
			(layers "F.Cu" "F.Mask" "F.Paste")
			(net "CLK_100M_CPU0_CLK01_R_DP")
		)
		(pad "A9" smd circle
			(at -26.640028 -36.809934 180)
			(size 0.450088 0.450088)
			(layers "F.Cu" "F.Mask" "F.Paste")
			(net "GND")
		)
		(pad "A10" smd circle
			(at -25.699974 -36.809934 180)
			(size 0.450088 0.450088)
			(layers "F.Cu" "F.Mask" "F.Paste")
			(net "CLK_100M_CPU0_CLK03_R_DP")
		)
		(pad "A11" smd circle
			(at -24.75992 -36.809934 180)
			(size 0.450088 0.450088)
			(layers "F.Cu" "F.Mask" "F.Paste")
			(net "CLK_100M_CPU0_CLK03_R_DN")
		)
		(pad "A13" smd circle
			(at -22.880066 -36.809934 180)
			(size 0.450088 0.450088)
			(layers "F.Cu" "F.Mask" "F.Paste")
			(net "FAB_REV_ID2")
		)
		(pad "A14" smd circle
			(at -21.940012 -36.809934 180)
			(size 0.450088 0.450088)
			(layers "F.Cu" "F.Mask" "F.Paste")
			(net "FAB_REV_ID0")
		)
		(pad "A15" smd circle
			(at -20.999958 -36.809934 180)
			(size 0.450088 0.450088)
			(layers "F.Cu" "F.Mask" "F.Paste")
			(net "GND")
		)
		(pad "A16" smd circle
			(at -20.059904 -36.809934 180)
			(size 0.450088 0.450088)
			(layers "F.Cu" "F.Mask" "F.Paste")
			(net "JTAG_CPU0_TMS")
		)
		(pad "A17" smd circle
			(at -19.120104 -36.809934 180)
			(size 0.450088 0.450088)
			(layers "F.Cu" "F.Mask" "F.Paste")
			(net "JTAG_CPU0_TRST_N")
		)
		(pad "A19" smd circle
			(at -17.239996 -36.809934 180)
			(size 0.450088 0.450088)
			(layers "F.Cu" "F.Mask" "F.Paste")
			(net "CLK_100M_REF_OUT_DP")
		)
		(pad "A20" smd circle
			(at -16.299942 -36.809934 180)
			(size 0.450088 0.450088)
			(layers "F.Cu" "F.Mask" "F.Paste")
			(net "CLK_100M_REF_OUT_DN")
		)
		(pad "A21" smd circle
			(at -15.359888 -36.809934 180)
			(size 0.450088 0.450088)
			(layers "F.Cu" "F.Mask" "F.Paste")
			(net "GND")
		)
		(pad "A22" smd circle
			(at -14.420088 -36.809934 180)
			(size 0.450088 0.450088)
			(layers "F.Cu" "F.Mask" "F.Paste")
			(net "SVID_PVDDCR_CPU0_P0_SVD")
		)
		(pad "A23" smd circle
			(at -13.480034 -36.809934 180)
			(size 0.450088 0.450088)
			(layers "F.Cu" "F.Mask" "F.Paste")
			(net "SVID_PVDDCR_CPU0_P0_SVC")
		)
		(pad "A25" smd circle
			(at -11.599926 -36.809934 180)
			(size 0.450088 0.450088)
			(layers "F.Cu" "F.Mask" "F.Paste")
			(net "USB2_CPU0_P0_DN")
		)
		(pad "A26" smd circle
			(at -10.659872 -36.809934 180)
			(size 0.450088 0.450088)
			(layers "F.Cu" "F.Mask" "F.Paste")
			(net "USB2_CPU0_P0_DP")
		)
		(pad "A27" smd circle
			(at -9.720072 -36.809934 180)
			(size 0.450088 0.450088)
			(layers "F.Cu" "F.Mask" "F.Paste")
			(net "GND")
		)
		(pad "A28" smd circle
			(at -8.780018 -36.809934 180)
			(size 0.450088 0.450088)
			(layers "F.Cu" "F.Mask" "F.Paste")
			(net "USB2_CPU0_P1_DP")
		)
		(pad "A29" smd circle
			(at -7.839964 -36.809934 180)
			(size 0.450088 0.450088)
			(layers "F.Cu" "F.Mask" "F.Paste")
			(net "USB2_CPU0_P1_DN")
		)
		(pad "A31" smd circle
			(at -5.96011 -36.809934 180)
			(size 0.450088 0.450088)
			(layers "F.Cu" "F.Mask" "F.Paste")
			(net "Net_1898")
		)
		(pad "A32" smd circle
			(at -5.020056 -36.809934 180)
			(size 0.450088 0.450088)
			(layers "F.Cu" "F.Mask" "F.Paste")
			(net "NC_CPU0_AZ_SDOUT")
		)
		(pad "A33" smd circle
			(at -4.080002 -36.809934 180)
			(size 0.450088 0.450088)
			(layers "F.Cu" "F.Mask" "F.Paste")
			(net "NC_CPU0_AZ_SDIN2")
		)
		(pad "A34" smd circle
			(at -3.139948 -36.809934 180)
			(size 0.450088 0.450088)
			(layers "F.Cu" "F.Mask" "F.Paste")
			(net "NC_CPU0_AZ_RST_N")
		)
		(pad "A35" smd circle
			(at -2.199894 -36.809934 180)
			(size 0.450088 0.450088)
			(layers "F.Cu" "F.Mask" "F.Paste")
			(net "Net_1899")
		)
		(pad "A41" smd circle
			(at 2.500122 -36.809934 180)
			(size 0.450088 0.450088)
			(layers "F.Cu" "F.Mask" "F.Paste")
			(net "Net_1900")
		)
		(pad "A42" smd circle
			(at 3.439922 -36.809934 180)
			(size 0.450088 0.450088)
			(layers "F.Cu" "F.Mask" "F.Paste")
			(net "Net_1901")
		)
		(pad "A43" smd circle
			(at 4.379976 -36.809934 180)
			(size 0.450088 0.450088)
			(layers "F.Cu" "F.Mask" "F.Paste")
			(net "GND")
		)
		(pad "A44" smd circle
			(at 5.32003 -36.809934 180)
			(size 0.450088 0.450088)
			(layers "F.Cu" "F.Mask" "F.Paste")
			(net "GND")
		)
		(pad "A45" smd circle
			(at 6.260084 -36.809934 180)
			(size 0.450088 0.450088)
			(layers "F.Cu" "F.Mask" "F.Paste")
			(net "Net_1902")
		)
		(pad "A47" smd circle
			(at 8.139938 -36.809934 180)
			(size 0.450088 0.450088)
			(layers "F.Cu" "F.Mask" "F.Paste")
			(net "GND")
		)
		(pad "A48" smd circle
			(at 9.079992 -36.809934 180)
			(size 0.450088 0.450088)
			(layers "F.Cu" "F.Mask" "F.Paste")
			(net "Net_1903")
		)
		(pad "A49" smd circle
			(at 10.020046 -36.809934 180)
			(size 0.450088 0.450088)
			(layers "F.Cu" "F.Mask" "F.Paste")
			(net "GND")
		)
		(pad "A50" smd circle
			(at 10.9601 -36.809934 180)
			(size 0.450088 0.450088)
			(layers "F.Cu" "F.Mask" "F.Paste")
			(net "Net_1904")
		)
		(pad "A51" smd circle
			(at 11.8999 -36.809934 180)
			(size 0.450088 0.450088)
			(layers "F.Cu" "F.Mask" "F.Paste")
			(net "Net_1905")
		)
		(pad "A53" smd circle
			(at 13.780008 -36.809934 180)
			(size 0.450088 0.450088)
			(layers "F.Cu" "F.Mask" "F.Paste")
			(net "GND")
		)
		(pad "A54" smd circle
			(at 14.720062 -36.809934 180)
			(size 0.450088 0.450088)
			(layers "F.Cu" "F.Mask" "F.Paste")
			(net "Net_1906")
		)
		(pad "A55" smd circle
			(at 15.660116 -36.809934 180)
			(size 0.450088 0.450088)
			(layers "F.Cu" "F.Mask" "F.Paste")
			(net "Net_1907")
		)
		(pad "A56" smd circle
			(at 16.599916 -36.809934 180)
			(size 0.450088 0.450088)
			(layers "F.Cu" "F.Mask" "F.Paste")
			(net "Net_1908")
		)
		(pad "A57" smd circle
			(at 17.53997 -36.809934 180)
			(size 0.450088 0.450088)
			(layers "F.Cu" "F.Mask" "F.Paste")
			(net "Net_1909")
		)
		(pad "A59" smd circle
			(at 19.420078 -36.809934 180)
			(size 0.450088 0.450088)
			(layers "F.Cu" "F.Mask" "F.Paste")
			(net "Net_1910")
		)
		(pad "A60" smd circle
			(at 20.359878 -36.809934 180)
			(size 0.450088 0.450088)
			(layers "F.Cu" "F.Mask" "F.Paste")
			(net "Net_1911")
		)
		(pad "A61" smd circle
			(at 21.299932 -36.809934 180)
			(size 0.450088 0.450088)
			(layers "F.Cu" "F.Mask" "F.Paste")
			(net "GND")
		)
		(pad "A62" smd circle
			(at 22.239986 -36.809934 180)
			(size 0.450088 0.450088)
			(layers "F.Cu" "F.Mask" "F.Paste")
			(net "CPU0_BP3")
		)
		(pad "A63" smd circle
			(at 23.18004 -36.809934 180)
			(size 0.450088 0.450088)
			(layers "F.Cu" "F.Mask" "F.Paste")
			(net "CPU0_BP2")
		)
		(pad "A65" smd circle
			(at 25.059894 -36.809934 180)
			(size 0.450088 0.450088)
			(layers "F.Cu" "F.Mask" "F.Paste")
			(net "CPU0_XTRIG_R2_L7")
		)
		(pad "A66" smd circle
			(at 25.999948 -36.809934 180)
			(size 0.450088 0.450088)
			(layers "F.Cu" "F.Mask" "F.Paste")
			(net "CPU0_XTRIG_R2_L6")
		)
		(pad "A67" smd circle
			(at 26.940002 -36.809934 180)
			(size 0.450088 0.450088)
			(layers "F.Cu" "F.Mask" "F.Paste")
			(net "GND")
		)
		(pad "A68" smd circle
			(at 27.880056 -36.809934 180)
			(size 0.450088 0.450088)
			(layers "F.Cu" "F.Mask" "F.Paste")
			(net "APML_CPU0_ALERT_N")
		)
		(pad "A69" smd circle
			(at 28.82011 -36.809934 180)
			(size 0.450088 0.450088)
			(layers "F.Cu" "F.Mask" "F.Paste")
			(net "CPU0_PROCHOT_N")
		)
		(pad "A71" smd circle
			(at 30.699964 -36.809934 180)
			(size 0.450088 0.450088)
			(layers "F.Cu" "F.Mask" "F.Paste")
			(net "I3C_0_SPD_DDRAF_CPU0_R_SCL")
		)
		(pad "A72" smd circle
			(at 31.640018 -36.809934 180)
			(size 0.450088 0.450088)
			(layers "F.Cu" "F.Mask" "F.Paste")
			(net "GND")
		)
		(pad "A73" smd circle
			(at 32.580072 -36.809934 180)
			(size 0.450088 0.450088)
			(layers "F.Cu" "F.Mask" "F.Paste")
			(net "GND")
		)
		(pad "AA1" smd circle
			(at -34.159952 -20.610068 180)
			(size 0.450088 0.450088)
			(layers "F.Cu" "F.Mask" "F.Paste")
			(net "GND")
		)
		(pad "AA2" smd circle
			(at -33.219898 -20.610068 180)
			(size 0.450088 0.450088)
			(layers "F.Cu" "F.Mask" "F.Paste")
			(net "M_G_CPU0_SA_DQ<20>")
		)
		(pad "AA3" smd circle
			(at -32.280098 -20.610068 180)
			(size 0.450088 0.450088)
			(layers "F.Cu" "F.Mask" "F.Paste")
			(net "M_G_CPU0_SA_DQS_DP<7>")
		)
		(pad "AA4" smd circle
			(at -31.340044 -20.610068 180)
			(size 0.450088 0.450088)
			(layers "F.Cu" "F.Mask" "F.Paste")
			(net "GND")
		)
		(pad "AA5" smd circle
			(at -30.39999 -20.610068 180)
			(size 0.450088 0.450088)
			(layers "F.Cu" "F.Mask" "F.Paste")
			(net "M_K_CPU0_SA_DQ<20>")
		)
		(pad "AA6" smd circle
			(at -29.459936 -20.610068 180)
			(size 0.450088 0.450088)
			(layers "F.Cu" "F.Mask" "F.Paste")
			(net "GND")
		)
		(pad "AA7" smd circle
			(at -28.519882 -20.610068 180)
			(size 0.450088 0.450088)
			(layers "F.Cu" "F.Mask" "F.Paste")
			(net "M_K_CPU0_SA_DQS_DP<7>")
		)
		(pad "AA8" smd circle
			(at -27.580082 -20.610068 180)
			(size 0.450088 0.450088)
			(layers "F.Cu" "F.Mask" "F.Paste")
			(net "GND")
		)
		(pad "AA9" smd circle
			(at -26.640028 -20.610068 180)
			(size 0.450088 0.450088)
			(layers "F.Cu" "F.Mask" "F.Paste")
			(net "M_L_CPU0_SA_DQ<20>")
		)
		(pad "AA10" smd circle
			(at -25.699974 -20.610068 180)
			(size 0.450088 0.450088)
			(layers "F.Cu" "F.Mask" "F.Paste")
			(net "M_L_CPU0_SA_DQS_DP<7>")
		)
		(pad "AA11" smd circle
			(at -24.75992 -20.610068 180)
			(size 0.450088 0.450088)
			(layers "F.Cu" "F.Mask" "F.Paste")
			(net "GND")
		)
		(pad "AA12" smd circle
			(at -23.82012 -20.610068 180)
			(size 0.450088 0.450088)
			(layers "F.Cu" "F.Mask" "F.Paste")
			(net "M_H_CPU0_SA_DQ<20>")
		)
		(pad "AA13" smd circle
			(at -22.880066 -20.610068 180)
			(size 0.450088 0.450088)
			(layers "F.Cu" "F.Mask" "F.Paste")
			(net "GND")
		)
		(pad "AA14" smd circle
			(at -21.940012 -20.610068 180)
			(size 0.450088 0.450088)
			(layers "F.Cu" "F.Mask" "F.Paste")
			(net "M_H_CPU0_SA_DQS_DP<7>")
		)
		(pad "AA15" smd circle
			(at -20.999958 -20.610068 180)
			(size 0.450088 0.450088)
			(layers "F.Cu" "F.Mask" "F.Paste")
			(net "GND")
		)
		(pad "AA16" smd circle
			(at -20.059904 -20.610068 180)
			(size 0.450088 0.450088)
			(layers "F.Cu" "F.Mask" "F.Paste")
			(net "M_J_CPU0_SA_DQ<20>")
		)
		(pad "AA17" smd circle
			(at -19.120104 -20.610068 180)
			(size 0.450088 0.450088)
			(layers "F.Cu" "F.Mask" "F.Paste")
			(net "M_J_CPU0_SA_DQS_DP<7>")
		)
		(pad "AA18" smd circle
			(at -18.18005 -20.610068 180)
			(size 0.450088 0.450088)
			(layers "F.Cu" "F.Mask" "F.Paste")
			(net "GND")
		)
		(pad "AA19" smd circle
			(at -17.239996 -20.610068 180)
			(size 0.450088 0.450088)
			(layers "F.Cu" "F.Mask" "F.Paste")
			(net "M_I_CPU0_SA_DQ<20>")
		)
		(pad "AA20" smd circle
			(at -16.299942 -20.610068 180)
			(size 0.450088 0.450088)
			(layers "F.Cu" "F.Mask" "F.Paste")
			(net "GND")
		)
		(pad "AA21" smd circle
			(at -15.359888 -20.610068 180)
			(size 0.450088 0.450088)
			(layers "F.Cu" "F.Mask" "F.Paste")
			(net "M_I_CPU0_SA_DQS_DP<7>")
		)
		(pad "AA22" smd circle
			(at -14.420088 -20.610068 180)
			(size 0.450088 0.450088)
			(layers "F.Cu" "F.Mask" "F.Paste")
			(net "PVDDCR_SOC_P0")
		)
		(pad "AA23" smd circle
			(at -13.480034 -20.610068 180)
			(size 0.450088 0.450088)
			(layers "F.Cu" "F.Mask" "F.Paste")
			(net "TP_CPU0_TEST6_X3D4")
		)
		(pad "AA24" smd circle
			(at -12.53998 -20.610068 180)
			(size 0.450088 0.450088)
			(layers "F.Cu" "F.Mask" "F.Paste")
			(net "TP_CPU0_TEST5_IOD")
		)
		(pad "AA25" smd circle
			(at -11.599926 -20.610068 180)
			(size 0.450088 0.450088)
			(layers "F.Cu" "F.Mask" "F.Paste")
			(net "TP_CPU0_TEST4_IOD")
		)
		(pad "AA26" smd circle
			(at -10.659872 -20.610068 180)
			(size 0.450088 0.450088)
			(layers "F.Cu" "F.Mask" "F.Paste")
			(net "TP_CPU0_TEST5_CCD7")
		)
		(pad "AA27" smd circle
			(at -9.720072 -20.610068 180)
			(size 0.450088 0.450088)
			(layers "F.Cu" "F.Mask" "F.Paste")
			(net "TP_CPU0_TEST4_CCD7")
		)
		(pad "AA28" smd circle
			(at -8.780018 -20.610068 180)
			(size 0.450088 0.450088)
			(layers "F.Cu" "F.Mask" "F.Paste")
			(net "TP_CPU0_TEST4_CCD11")
		)
		(pad "AA29" smd circle
			(at -7.839964 -20.610068 180)
			(size 0.450088 0.450088)
			(layers "F.Cu" "F.Mask" "F.Paste")
			(net "TP_CPU0_TEST6_X3D2")
		)
		(pad "AA30" smd circle
			(at -6.89991 -20.610068 180)
			(size 0.450088 0.450088)
			(layers "F.Cu" "F.Mask" "F.Paste")
			(net "TP_CPU0_TEST4_CCD3")
		)
		(pad "AA31" smd circle
			(at -5.96011 -20.610068 180)
			(size 0.450088 0.450088)
			(layers "F.Cu" "F.Mask" "F.Paste")
			(net "GND")
		)
		(pad "AA32" smd circle
			(at -5.020056 -20.610068 180)
			(size 0.450088 0.450088)
			(layers "F.Cu" "F.Mask" "F.Paste")
			(net "GMI_CPU1_G0_CPU0_G2_TX_DN<11>")
		)
		(pad "AA33" smd circle
			(at -4.080002 -20.610068 180)
			(size 0.450088 0.450088)
			(layers "F.Cu" "F.Mask" "F.Paste")
			(net "GMI_CPU1_G0_CPU0_G2_TX_DP<11>")
		)
		(pad "AA34" smd circle
			(at -3.139948 -20.610068 180)
			(size 0.450088 0.450088)
			(layers "F.Cu" "F.Mask" "F.Paste")
			(net "GND")
		)
		(pad "AA35" smd circle
			(at -2.199894 -20.610068 180)
			(size 0.450088 0.450088)
			(layers "F.Cu" "F.Mask" "F.Paste")
			(net "GND")
		)
		(pad "AA36" smd circle
			(at -1.260094 -20.610068 180)
			(size 0.450088 0.450088)
			(layers "F.Cu" "F.Mask" "F.Paste")
			(net "GND")
		)
		(pad "AA40" smd circle
			(at 1.560068 -20.610068 180)
			(size 0.450088 0.450088)
			(layers "F.Cu" "F.Mask" "F.Paste")
			(net "GND")
		)
		(pad "AA41" smd circle
			(at 2.500122 -20.610068 180)
			(size 0.450088 0.450088)
			(layers "F.Cu" "F.Mask" "F.Paste")
			(net "GND")
		)
		(pad "AA42" smd circle
			(at 3.439922 -20.610068 180)
			(size 0.450088 0.450088)
			(layers "F.Cu" "F.Mask" "F.Paste")
			(net "GND")
		)
		(pad "AA43" smd circle
			(at 4.379976 -20.610068 180)
			(size 0.450088 0.450088)
			(layers "F.Cu" "F.Mask" "F.Paste")
			(net "GMI_CPU0_G0_CPU1_G2_TX_DP<4>")
		)
		(pad "AA44" smd circle
			(at 5.32003 -20.610068 180)
			(size 0.450088 0.450088)
			(layers "F.Cu" "F.Mask" "F.Paste")
			(net "GMI_CPU0_G0_CPU1_G2_TX_DN<4>")
		)
		(pad "AA45" smd circle
			(at 6.260084 -20.610068 180)
			(size 0.450088 0.450088)
			(layers "F.Cu" "F.Mask" "F.Paste")
			(net "GND")
		)
		(pad "AA46" smd circle
			(at 7.199884 -20.610068 180)
			(size 0.450088 0.450088)
			(layers "F.Cu" "F.Mask" "F.Paste")
			(net "TP_CPU0_TEST6_CCD0")
		)
		(pad "AA47" smd circle
			(at 8.139938 -20.610068 180)
			(size 0.450088 0.450088)
			(layers "F.Cu" "F.Mask" "F.Paste")
			(net "TP_CPU0_TEST6_X3D0")
		)
		(pad "AA48" smd circle
			(at 9.079992 -20.610068 180)
			(size 0.450088 0.450088)
			(layers "F.Cu" "F.Mask" "F.Paste")
			(net "TP_CPU0_TEST4_CCD8")
		)
		(pad "AA49" smd circle
			(at 10.020046 -20.610068 180)
			(size 0.450088 0.450088)
			(layers "F.Cu" "F.Mask" "F.Paste")
			(net "TP_CPU0_TEST6_IOD")
		)
		(pad "AA50" smd circle
			(at 10.9601 -20.610068 180)
			(size 0.450088 0.450088)
			(layers "F.Cu" "F.Mask" "F.Paste")
			(net "TP_CPU0_TEST4_CCD0")
		)
	)
)
